FILE_TYPE = CONNECTIVITY;
{Allegro Design Entry HDL 17.4-2019 S026 (4007227) 1/17/2022}
"PAGE_NUMBER" = 342;
0"NC";
1"GND\g";
2"GND\g";
3"GND\g";
4"P3V3_AUX\g";
5"GND\g";
6"GND\g";
7"GND\g";
8"GND\g";
9"P3V3_AUX\g";
10"GND\g";
11"GND\g";
12"P3V3_AUX\g";
13"GND\g";
14"GND\g";
15"GND\g";
16"GND\g";
17"P3V3_AUX\g";
18"RST_PERST_OCP_V3_2_BUF_N"CDS_PHYS_NET_NAME"RST_HP_OCP_V3_2_N";
19"RST_PERST_OCP_V3_2_BUF2_N"CDS_PHYS_NET_NAME"RST_OCP_V3_2_BUF_N";
20"IRQ_LVC3_OCP_V3_2_WAKE_N"CDS_PHYS_NET_NAME"IRQ_LVC3_OCP_V3_2_WAKE_N";
21"PU_OCP_V3_2_WAKE_OE"CDS_PHYS_NET_NAME"PU_OCP_V3_2_WAKE_OE";
22"OCP_V3_2_AUX_PWR_EN"CDS_PHYS_NET_NAME"OCP_V3_2_AUX_PWR_EN";
23"RST_SMB_SWITCH_N"CDS_PHYS_NET_NAME"RST_SMB_SWITCH_N";
24"OCP_V3_2_AUX_PWR_EN_R3"CDS_PHYS_NET_NAME"OCP_V3_2_AUX_PWR_EN_R3";
25"FM_SYS_THROTTLE_N"CDS_PHYS_NET_NAME"FM_SYS_THROTTLE_N";
26"NC_U218_NC1"CDS_PHYS_NET_NAME"NC_U218_NC1";
27"OCP_V3_2_WAKE_BUFF_N"CDS_PHYS_NET_NAME"OCP_V3_2_WAKE_BUFF_N";
28"RST_HP_OCP_V3_2_R_N";
29"RST_SMB_OCP_V3_2_N";
30"CLK_50M_NCSI_OCP_V3_2_ISO"CDS_PHYS_NET_NAME"CLK_50M_NCSI_OCP_V3_2_ISO";
31"OCP_V3_2_PWRBRK_BUFF_N"CDS_PHYS_NET_NAME"OCP_V3_2_PWRBRK_BUFF_N";
32"IRQ_OCP_V3_2_WAKE_BUF_N"CDS_PHYS_NET_NAME"IRQ_LVC3_WAKE_N";
33"IRQ_LVC3_V3_2_WAKE_BUF_N"CDS_PHYS_NET_NAME"IRQ_LVC3_V3_2_WAKE_BUF_N";
34"OCP_V3_2_PWRBRK_N"CDS_PHYS_NET_NAME"OCP_V3_2_PWRBRK_N";
35"NC_U219_NC1"CDS_PHYS_NET_NAME"NC_U219_NC1";
36"OCP_V3_2_WAKE_BUFF_R_N"CDS_PHYS_NET_NAME"OCP_V3_2_WAKE_BUFF_R_N";
37"RST_PERST0_OCP_V3_2_N";
38"RST_PERST1_OCP_V3_2_N";
39"RST_PERST2_OCP_V3_2_N";
40"RST_PERST3_OCP_V3_2_N";
41"P3V3_AUX\g";
42"P3V3_OCP_V3_2\g";
43"P3V3_AUX\g";
44"P3V3_AUX\g"$PHYS_NET_NAME"P3V3_AUX"CDS_PHYS_NET_NAME"P3V3_AUX"VOLTAGE"3.3";
45"P3V3_AUX\g";
46"CLK_50M_NCSI_OCP_V3_2"CDS_PHYS_NET_NAME"CLK_50M_NCSI_OCP_V3_2";
47"FB_BMC_ISOLATE1";
48"P3V3_AUX\g";
49"CLK_50M_NCSI_OCP_V3_2_ISO_R"CDS_PHYS_NET_NAME"CLK_50M_NCSI_OCP_V3_2_ISO_R";
%"UNIVERSAL_GND"
"1","(5875,-3500)","0","pure_quanta_power","I10";
;
CDS_LIB"pure_quanta_power"
HDL_POWER"GND";
"A"1;
%"UNIVERSAL_GND"
"1","(5650,-2925)","0","pure_quanta_power","I11";
;
CDS_LIB"pure_quanta_power"
HDL_POWER"GND";
"A"2;
%"Q_CAP"
"1","(5650,-2700)","2","pure_quanta","I12";
;
LOCATION"C1841"
$SEC"1"
CDS_SEC"1"
VALUE"0.1UF"
VOLTAGE"25V"
MATERIAL"X7R"
PACK_TYPE"0402"
TOLERANCE"10%"
CDS_LIB"pure_quanta"
PART_NUMBER"CH4104K1B00";
"B"
$PN"2"2;
"A"
$PN"1"45;
%"UNIVERSAL_POWER"
"1","(5650,-2400)","0","pure_quanta_power","I13";
;
HDL_POWER"P3V3_AUX"
CDS_LIB"pure_quanta_power";
"A"45;
%"74LVC1G126SE7"
"1","(4850,-1725)","0","pure_quanta","I14";
;
LOCATION"U217"
$SEC"1"
CDS_SEC"1"
MATERIAL"IC"
VALUE"74LVC1G126SE-7"
PART_TYPE"SMLF"
CDS_LIB"pure_quanta"
CDS_LMAN_SYM_OUTLINE"-100,100,100,-100"
NEEDS_NO_SIZE"TRUE"
PART_NUMBER"AL1G0126009";
"OE"
$PN"1"21;
"GND"
$PN"3"16;
"VCC"
$PN"5"44;
"Y"
$PN"4"27;
"A"
$PN"2"20;
%"Q_CAP"
"1","(5150,-1225)","0","pure_quanta","I16";
;
LOCATION"C1822"
$SEC"1"
CDS_SEC"1"
VOLTAGE"25V"
PACK_TYPE"0402"
MATERIAL"X7R"
TOLERANCE"10%"
VALUE"0.1UF"
CDS_LIB"pure_quanta"
PART_NUMBER"CH4104K1B00";
"B"
$PN"2"3;
"A"
$PN"1"44;
%"UNIVERSAL_GND"
"1","(5150,-1450)","0","pure_quanta_power","I17";
;
CDS_LIB"pure_quanta_power"
HDL_POWER"GND";
"A"3;
%"Q_RES"
"2","(5975,-1275)","0","pure_quanta","I18";
;
LOCATION"R3184"
$SEC"1"
CDS_SEC"1"
MATERIAL"CHIP"
WATTAGE"1/16W"
TOLERANCE"1%"
PACK_TYPE"0402LF"
VALUE"4.7K"
CDS_LIB"pure_quanta"
PART_NUMBER"CS24702FB06";
"A"
$PN"1"4;
"B"
$PN"2"27;
%"UNIVERSAL_POWER"
"1","(5975,-1075)","0","pure_quanta_power","I19";
;
HDL_POWER"P3V3_AUX"
CDS_LIB"pure_quanta_power";
"A"4;
%"UNIVERSAL_POWER"
"1","(5150,-900)","0","pure_quanta_power","I20";
;
HDL_POWER"P3V3_AUX"
CDS_LIB"pure_quanta_power";
"A"44;
%"UNIVERSAL_GND"
"1","(5300,-725)","0","pure_quanta_power","I21";
;
CDS_LIB"pure_quanta_power"
HDL_POWER"GND";
"A"5;
%"74LVC1G07GV"
"1","(5775,-400)","0","pure_quanta","I22";
;
LOCATION"U218"
$SEC"1"
CDS_SEC"1"
VALUE"74LVC1G07GV"
PART_TYPE"SMLF"
MATERIAL"IC"
CDS_LIB"pure_quanta"
NEEDS_NO_SIZE"TRUE"
CDS_LMAN_SYM_OUTLINE"-125,150,125,-150"
PART_NUMBER"AL1G0007001";
"NC1"
$PN"1"26;
"Y"
$PN"4"31;
"GND"
$PN"3"5;
"A"
$PN"2"25;
"VCC"
$PN"5"41;
%"UNIVERSAL_GND"
"1","(6825,-3550)","0","pure_quanta_power","I23";
;
CDS_LIB"pure_quanta_power"
HDL_POWER"GND";
"A"6;
%"Q_RES"
"2","(6825,-3325)","0","pure_quanta","I24";
;
LOCATION"R3235"
$SEC"1"
CDS_SEC"1"
TOLERANCE"1%"
WATTAGE"1/16W"
MATERIAL"CHIP"
PACK_TYPE"0402LF"
VALUE"100K"
CDS_LIB"pure_quanta"
PART_NUMBER"CS41002FB09";
"A"
$PN"1"28;
"B"
$PN"2"6;
%"Q_RES"
"1","(7100,-3125)","0","pure_quanta","I25";
;
LOCATION"R3236"
$SEC"1"
CDS_SEC"1"
VALUE"0"
PACK_TYPE"0402LF"
MATERIAL"CHIP"
TOLERANCE"5%"
WATTAGE"1/16W"
CDS_LIB"pure_quanta"
PART_NUMBER"CS00002JB13";
"B"
$PN"2"29;
"A"
$PN"1"28;
%"UNIVERSAL_GND"
"1","(7600,-2050)","0","pure_quanta_power","I28";
;
CDS_LIB"pure_quanta_power"
HDL_POWER"GND";
"A"7;
%"Q_RES"
"1","(6300,-1725)","0","pure_quanta","I29";
;
LOCATION"R3185"
$SEC"1"
CDS_SEC"1"
MATERIAL"CHIP"
VALUE"33.2"
TOLERANCE"1%"
WATTAGE"1/16W"
PACK_TYPE"0402LF"
CDS_LIB"pure_quanta"
PART_NUMBER"CS03322FB03";
"B"
$PN"2"36;
"A"
$PN"1"27;
%"Q_RES"
"2","(3350,-1375)","2","pure_quanta","I3";
;
LOCATION"R3182"
$SEC"1"
CDS_SEC"1"
MATERIAL"CHIP"
PACK_TYPE"0402LF"
WATTAGE"1/16W"
TOLERANCE"1%"
VALUE"10K"
CDS_LIB"pure_quanta"
PART_NUMBER"CS31002FB08";
"A"
$PN"1"42;
"B"
$PN"2"20;
%"UNIVERSAL_GND"
"1","(6450,-250)","0","pure_quanta_power","I30";
;
CDS_LIB"pure_quanta_power"
HDL_POWER"GND";
"A"8;
%"Q_CAP"
"1","(6450,-25)","0","pure_quanta","I31";
;
LOCATION"C1823"
$SEC"1"
CDS_SEC"1"
PACK_TYPE"0402"
TOLERANCE"10%"
MATERIAL"X7R"
VALUE"0.1UF"
VOLTAGE"25V"
CDS_LIB"pure_quanta"
PART_NUMBER"CH4104K1B00";
"B"
$PN"2"8;
"A"
$PN"1"41;
%"74LVC1G07GV"
"1","(8075,-1725)","0","pure_quanta","I32";
;
LOCATION"U219"
$SEC"1"
CDS_SEC"1"
PART_TYPE"SMLF"
VALUE"74LVC1G07GV"
MATERIAL"IC"
CDS_LIB"pure_quanta"
CDS_LMAN_SYM_OUTLINE"-125,150,125,-150"
NEEDS_NO_SIZE"TRUE"
PART_NUMBER"AL1G0007001";
"NC1"
$PN"1"35;
"Y"
$PN"4"33;
"GND"
$PN"3"7;
"A"
$PN"2"36;
"VCC"
$PN"5"43;
%"Q_RES"
"1","(7700,-500)","0","pure_quanta","I33";
;
LOCATION"R3191"
$SEC"1"
CDS_SEC"1"
PACK_TYPE"0402LF"
MATERIAL"CHIP"
VALUE"33.2"
WATTAGE"1/16W"
TOLERANCE"1%"
CDS_LIB"pure_quanta"
PART_NUMBER"CS03322FB03";
"B"
$PN"2"34;
"A"
$PN"1"31;
%"Q_RES"
"2","(7150,-125)","0","pure_quanta","I34";
;
LOCATION"R3190"
$SEC"1"
CDS_SEC"1"
VALUE"4.7K"
TOLERANCE"1%"
MATERIAL"CHIP"
PACK_TYPE"0402LF"
WATTAGE"1/16W"
CDS_LIB"pure_quanta"
PART_NUMBER"CS24702FB06";
"A"
$PN"1"9;
"B"
$PN"2"31;
%"UNIVERSAL_POWER"
"1","(7150,75)","0","pure_quanta_power","I35";
;
HDL_POWER"P3V3_AUX"
CDS_LIB"pure_quanta_power";
"A"9;
%"Q_RES"
"1","(8575,-3425)","0","pure_quanta","I36";
;
LOCATION"R4602"
$SEC"1"
CDS_SEC"1"
MATERIAL"CHIP"
VALUE"0"
CDS_LIB"pure_quanta"
PACK_TYPE"0402LF"
TOLERANCE"5%"
WATTAGE"1/16W"
PART_NUMBER"CS00002JB13";
"B"
$PN"2"49;
"A"
$PN"1"30;
%"UNIVERSAL_GND"
"1","(9700,-3675)","0","pure_quanta_power","I38";
;
CDS_LIB"pure_quanta_power"
HDL_POWER"GND";
"A"10;
%"UNIVERSAL_POWER"
"1","(8500,-1175)","0","pure_quanta_power","I39";
;
HDL_POWER"P3V3_AUX"
CDS_LIB"pure_quanta_power";
"A"43;
%"Q_RES"
"2","(3625,-1375)","0","pure_quanta","I4";
;
LOCATION"R3183"
$SEC"1"
CDS_SEC"1"
MATERIAL"CHIP"
WATTAGE"1/16W"
VALUE"10K"
TOLERANCE"1%"
PACK_TYPE"0402LF"
CDS_LIB"pure_quanta"
PART_NUMBER"CS31002FB08";
"A"
$PN"1"42;
"B"
$PN"2"21;
%"UNIVERSAL_GND"
"1","(8700,-1675)","0","pure_quanta_power","I40";
;
CDS_LIB"pure_quanta_power"
HDL_POWER"GND";
"A"11;
%"Q_CAP"
"1","(8700,-1450)","0","pure_quanta","I41";
;
LOCATION"C1824"
$SEC"1"
CDS_SEC"1"
VOLTAGE"25V"
TOLERANCE"10%"
VALUE"0.1UF"
MATERIAL"X7R"
PACK_TYPE"0402"
CDS_LIB"pure_quanta"
PART_NUMBER"CH4104K1B00";
"B"
$PN"2"11;
"A"
$PN"1"43;
%"Q_RES"
"1","(9550,-1825)","0","pure_quanta","I43";
;
LOCATION"R3193"
$SEC"1"
CDS_SEC"1"
TOLERANCE"1%"
VALUE"33.2"
PACK_TYPE"0402LF"
MATERIAL"CHIP"
WATTAGE"1/16W"
CDS_LIB"pure_quanta"
PART_NUMBER"CS03322FB03";
"B"
$PN"2"32;
"A"
$PN"1"33;
%"Q_RES"
"2","(9250,-1375)","0","pure_quanta","I44";
;
LOCATION"R3192"
$SEC"1"
CDS_SEC"1"
PACK_TYPE"0402LF"
MATERIAL"EMPTY"
TOLERANCE"1%"
VALUE"4.7K"
WATTAGE"1/16W"
CDS_LIB"pure_quanta"
PART_NUMBER"CS24702FB06";
"A"
$PN"1"12;
"B"
$PN"2"33;
%"UNIVERSAL_POWER"
"1","(9250,-1175)","0","pure_quanta_power","I45";
;
HDL_POWER"P3V3_AUX"
CDS_LIB"pure_quanta_power";
"A"12;
%"UNIVERSAL_GND"
"1","(10775,-3375)","0","pure_quanta_power","I46";
;
CDS_LIB"pure_quanta_power"
HDL_POWER"GND";
"A"13;
%"Q_CAP"
"1","(10775,-3150)","0","pure_quanta","I47";
;
LOCATION"C38"
$SEC"1"
CDS_SEC"1"
PACK_TYPE"0402"
MATERIAL"X7R"
TOLERANCE"10%"
VOLTAGE"25V"
VALUE"0.1UF"
CDS_LIB"pure_quanta"
PART_NUMBER"CH4104K1B00";
"B"
$PN"2"13;
"A"
$PN"1"48;
%"UNIVERSAL_POWER"
"1","(10575,-2875)","0","pure_quanta_power","I49";
;
HDL_POWER"P3V3_AUX"
CDS_LIB"pure_quanta_power";
"A"48;
%"UNIVERSAL_POWER"
"1","(3625,-1025)","0","pure_quanta_power","I5";
;
HDL_POWER"P3V3_OCP_V3_2"
CDS_LIB"pure_quanta_power";
"A"42;
%"UNIVERSAL_POWER"
"1","(6250,250)","0","pure_quanta_power","I51";
;
HDL_POWER"P3V3_AUX"
CDS_LIB"pure_quanta_power";
"A"41;
%"UNIVERSAL_GND"
"1","(4500,1025)","0","pure_quanta_power","I54";
;
CDS_LIB"pure_quanta_power"
HDL_POWER"GND";
"A"14;
%"Q_CAP"
"1","(4500,1250)","2","pure_quanta","I55";
;
LOCATION"C1821"
$SEC"1"
CDS_SEC"1"
VALUE"0.1UF"
VOLTAGE"25V"
TOLERANCE"10%"
PACK_TYPE"0402"
MATERIAL"X7R"
CDS_LIB"pure_quanta"
PART_NUMBER"CH4104K1B00";
"B"
$PN"2"14;
"A"
$PN"1"17;
%"UNIVERSAL_GND"
"1","(4825,675)","0","pure_quanta_power","I56";
;
CDS_LIB"pure_quanta_power"
HDL_POWER"GND";
"A"15;
%"UNIVERSAL_POWER"
"1","(4700,1525)","0","pure_quanta_power","I57";
;
HDL_POWER"P3V3_AUX"
CDS_LIB"pure_quanta_power";
"A"17;
%"74LVC1G17GW"
"1","(5000,925)","0","pure_quanta","I58";
;
LOCATION"U207"
SEC"1"
PART_TYPE"SMLF"
MATERIAL"IC"
VALUE"74LVC1G17GW"
SEC_TYPE""
CDS_LIB"pure_quanta"
CDS_LMAN_SYM_OUTLINE"-125,150,125,-150"
PIN_NAMES_ROTATE"True"
PART_NUMBER"AL1G0017K01";
"NC"
$PN"1"0;
"Y"
$PN"4"19;
"GND"
$PN"3"15;
"A"
$PN"2"18;
"VCC"
$PN"5"17;
%"Q_RES"
"1","(4300,-3175)","0","pure_quanta","I6";
;
LOCATION"R3234"
$SEC"1"
CDS_SEC"1"
PACK_TYPE"0402LF"
WATTAGE"1/16W"
MATERIAL"CHIP"
VALUE"33.2"
TOLERANCE"1%"
CDS_LIB"pure_quanta"
PART_NUMBER"CS03322FB03";
"B"
$PN"2"24;
"A"
$PN"1"22;
%"Q_RES"
"1","(6475,925)","0","pure_quanta","I72";
;
LOCATION"R6056"
$SEC"1"
CDS_SEC"1"
VALUE"0"
CDS_LIB"pure_quanta"
BOM_COST"MEM"
WATTAGE"1/16W"
MATERIAL"CHIP"
TOLERANCE"5%"
PACK_TYPE"0402LF"
PART_NUMBER"CS00002JB13";
"B"
$PN"2"37;
"A"
$PN"1"19;
%"Q_RES"
"1","(6475,875)","0","pure_quanta","I73";
;
LOCATION"R6057"
$SEC"1"
CDS_SEC"1"
VALUE"0"
CDS_LIB"pure_quanta"
BOM_COST"MEM"
WATTAGE"1/16W"
MATERIAL"CHIP"
TOLERANCE"5%"
PACK_TYPE"0402LF"
PART_NUMBER"CS00002JB13";
"B"
$PN"2"38;
"A"
$PN"1"19;
%"Q_RES"
"1","(6475,825)","0","pure_quanta","I74";
;
LOCATION"R6058"
$SEC"1"
CDS_SEC"1"
VALUE"0"
CDS_LIB"pure_quanta"
BOM_COST"MEM"
WATTAGE"1/16W"
MATERIAL"CHIP"
TOLERANCE"5%"
PACK_TYPE"0402LF"
PART_NUMBER"CS00002JB13";
"B"
$PN"2"39;
"A"
$PN"1"19;
%"Q_RES"
"1","(6475,775)","0","pure_quanta","I75";
;
LOCATION"R6059"
$SEC"1"
CDS_SEC"1"
VALUE"0"
CDS_LIB"pure_quanta"
BOM_COST"MEM"
WATTAGE"1/16W"
MATERIAL"CHIP"
TOLERANCE"5%"
PACK_TYPE"0402LF"
PART_NUMBER"CS00002JB13";
"B"
$PN"2"40;
"A"
$PN"1"19;
%"74LVC1G66GV"
"1","(10125,-3425)","0","pure_quanta","I76";
;
LOCATION"U321"
SEC"1"
PART_TYPE"SMLF"
MATERIAL"IC"
VALUE"74LVC1G66GV"
SEC_TYPE""
CDS_LIB"pure_quanta"
PIN_NAMES_ROTATE"True"
CDS_LMAN_SYM_OUTLINE"-150,150,150,-150"
PART_NUMBER"AL001G66000";
"VCC"
$PN"5"48;
"E"
$PN"4"47;
"GND"
$PN"3"10;
"Z"
$PN"2"49;
"Y"
$PN"1"46;
%"UNIVERSAL_GND"
"1","(4850,-2175)","0","pure_quanta_power","I8";
;
CDS_LIB"pure_quanta_power"
HDL_POWER"GND";
"A"16;
%"74LVC1G126SE7"
"1","(5875,-3125)","0","pure_quanta","I9";
;
LOCATION"U225"
$SEC"1"
CDS_SEC"1"
MATERIAL"IC"
PART_TYPE"SMLF"
VALUE"74LVC1G126SE-7"
CDS_LMAN_SYM_OUTLINE"-100,100,100,-100"
CDS_LIB"pure_quanta"
NEEDS_NO_SIZE"TRUE"
PART_NUMBER"AL1G0126009";
"OE"
$PN"1"24;
"GND"
$PN"3"1;
"VCC"
$PN"5"45;
"Y"
$PN"4"28;
"A"
$PN"2"23;
END.
